# SCM (Grand Teton) — schematic netlist excerpt (pin names and nets, part order shuffled) for the footprints in the layout excerpt that follows; sources: Cadence DE-HDL packaged netlist, KiCad conversion of 12092022_DA0F0TMDCD0_F0T_Management_Board_D_brd_V3_OCP.brd

R8  Q_RES  60.4 1% CHIP  pkg 0402LF  page 20 : A = M_BMC_DDR4_MCLK_DP ; B = M_BMC_DDR4_MCLK_C
C152  Q_CAP  0.1UF 25V 10% X7R  pkg 0402  page 41 : A = VCCIO3 ; B = GND

(kicad_pcb
	(version 20260206)
	(generator "pcbnew")
	(generator_version "10.0")
	(general
		(thickness 1.6)
		(legacy_teardrops no)
	)
	(paper "A4")
	(title_block
		(title "12092022_DA0F0TMDCD0_F0T_Management_Board_D_brd_V3_OCP.brd")
		(comment 1 "Grand Teton / footprints 1169-1170 of 1440")
	)
	(layers
		(0 "F.Cu" signal "TOP")
		(4 "In1.Cu" signal "GND")
		(6 "In2.Cu" signal "IN1")
		(8 "In3.Cu" signal "GND1")
		(10 "In4.Cu" signal "IN2")
		(12 "In5.Cu" signal "VCC")
		(14 "In6.Cu" signal "VCC1")
		(16 "In7.Cu" signal "IN3")
		(18 "In8.Cu" signal "GND2")
		(20 "In9.Cu" signal "IN4")
		(22 "In10.Cu" signal "GND3")
		(2 "B.Cu" signal "BOTTOM")
		(9 "F.Adhes" user "F.Adhesive")
		(11 "B.Adhes" user "B.Adhesive")
		(13 "F.Paste" user "Package Geometry/Pastemask Top")
		(15 "B.Paste" user "Package Geometry/Pastemask Bottom")
		(5 "F.SilkS" user "Ref Des/Silkscreen Top")
		(7 "B.SilkS" user "Ref Des/Silkscreen Bottom")
		(1 "F.Mask" user "Board Geometry/Soldermask Top")
		(3 "B.Mask" user "Board Geometry/Soldermask Bottom")
		(17 "Dwgs.User" user "User.Drawings")
		(19 "Cmts.User" user "User.Comments")
		(21 "Eco1.User" user "User.Eco1")
		(23 "Eco2.User" user "User.Eco2")
		(25 "Edge.Cuts" user "Board Geometry/Outline")
		(27 "Margin" user)
		(31 "F.CrtYd" user "Package Geometry/Place Bound Top")
		(29 "B.CrtYd" user "Package Geometry/Place Bound Bottom")
		(35 "F.Fab" user "Ref Des/Assembly Top")
		(33 "B.Fab" user "Ref Des/Assembly Bottom")
	)
	(footprint ""
		(layer "B.Cu")
		(at 26.3652 -97.282 -90)
		(property "Reference" "C152"
			(at 0 0 90)
			(layer "B.SilkS")
			(hide yes)
			(effects
				(font
					(size 1.27 1.27)
				)
				(justify mirror)
			)
		)
		(property "Value" ""
			(at 0 0 90)
			(layer "B.Fab")
			(effects
				(font
					(size 1.27 1.27)
				)
				(justify mirror)
			)
		)
		(duplicate_pad_numbers_are_jumpers no)
		(fp_line
			(start -0.7874 0.4064)
			(end 0.7874 0.4064)
			(stroke
				(width 0.1524)
				(type default)
			)
			(layer "B.SilkS")
		)
		(fp_line
			(start 0.7874 0.4064)
			(end 0.7874 -0.4064)
			(stroke
				(width 0.1524)
				(type default)
			)
			(layer "B.SilkS")
		)
		(fp_line
			(start -0.7874 -0.4064)
			(end -0.7874 0.4064)
			(stroke
				(width 0.1524)
				(type default)
			)
			(layer "B.SilkS")
		)
		(fp_line
			(start 0.7874 -0.4064)
			(end -0.7874 -0.4064)
			(stroke
				(width 0.1524)
				(type default)
			)
			(layer "B.SilkS")
		)
		(fp_line
			(start -0.67945 0.3048)
			(end -0.120396 0.3048)
			(stroke
				(width 0.1)
				(type default)
			)
			(layer "B.Fab")
		)
		(fp_line
			(start -0.120396 0.3048)
			(end -0.120396 0.2794)
			(stroke
				(width 0.1)
				(type default)
			)
			(layer "B.Fab")
		)
		(fp_line
			(start 0.12065 0.3048)
			(end 0.67945 0.3048)
			(stroke
				(width 0.1)
				(type default)
			)
			(layer "B.Fab")
		)
		(fp_line
			(start 0.67945 0.3048)
			(end 0.67945 -0.305054)
			(stroke
				(width 0.1)
				(type default)
			)
			(layer "B.Fab")
		)
		(fp_line
			(start -0.120396 0.2794)
			(end 0.12065 0.2794)
			(stroke
				(width 0.1)
				(type default)
			)
			(layer "B.Fab")
		)
		(fp_line
			(start 0.12065 0.2794)
			(end 0.12065 0.3048)
			(stroke
				(width 0.1)
				(type default)
			)
			(layer "B.Fab")
		)
		(fp_line
			(start -0.12065 -0.2794)
			(end -0.12065 -0.3048)
			(stroke
				(width 0.1)
				(type default)
			)
			(layer "B.Fab")
		)
		(fp_line
			(start 0.12065 -0.2794)
			(end -0.12065 -0.2794)
			(stroke
				(width 0.1)
				(type default)
			)
			(layer "B.Fab")
		)
		(fp_line
			(start -0.67945 -0.3048)
			(end -0.67945 0.3048)
			(stroke
				(width 0.1)
				(type default)
			)
			(layer "B.Fab")
		)
		(fp_line
			(start -0.12065 -0.3048)
			(end -0.67945 -0.3048)
			(stroke
				(width 0.1)
				(type default)
			)
			(layer "B.Fab")
		)
		(fp_line
			(start 0.12065 -0.305054)
			(end 0.12065 -0.2794)
			(stroke
				(width 0.1)
				(type default)
			)
			(layer "B.Fab")
		)
		(fp_line
			(start 0.67945 -0.305054)
			(end 0.12065 -0.305054)
			(stroke
				(width 0.1)
				(type default)
			)
			(layer "B.Fab")
		)
		(pad "1" smd circle
			(at 0.40005 0 90)
			(size 0 0)
			(layers "B.Cu" "B.Mask" "B.Paste")
			(net "VCCIO3")
		)
		(pad "2" smd circle
			(at -0.40005 0 90)
			(size 0 0)
			(layers "B.Cu" "B.Mask" "B.Paste")
			(net "GND")
		)
	)
	(footprint ""
		(layer "B.Cu")
		(at 76.982828 -47.21479)
		(property "Reference" "R8"
			(at 0 0 0)
			(layer "B.SilkS")
			(hide yes)
			(effects
				(font
					(size 1.27 1.27)
				)
				(justify mirror)
			)
		)
		(property "Value" ""
			(at 0 0 0)
			(layer "B.Fab")
			(effects
				(font
					(size 1.27 1.27)
				)
				(justify mirror)
			)
		)
		(duplicate_pad_numbers_are_jumpers no)
		(fp_line
			(start -0.7874 -0.4064)
			(end -0.7874 0.4064)
			(stroke
				(width 0.1524)
				(type default)
			)
			(layer "B.SilkS")
		)
		(fp_line
			(start -0.7874 0.4064)
			(end 0.487172 0.4064)
			(stroke
				(width 0.1524)
				(type default)
			)
			(layer "B.SilkS")
		)
		(fp_line
			(start 0.7874 -0.4064)
			(end -0.7874 -0.4064)
			(stroke
				(width 0.1524)
				(type default)
			)
			(layer "B.SilkS")
		)
		(fp_line
			(start 0.7874 0.09779)
			(end 0.7874 -0.4064)
			(stroke
				(width 0.1524)
				(type default)
			)
			(layer "B.SilkS")
		)
		(fp_line
			(start -0.67945 -0.3048)
			(end -0.67945 0.3048)
			(stroke
				(width 0.1)
				(type default)
			)
			(layer "B.Fab")
		)
		(fp_line
			(start -0.67945 0.3048)
			(end -0.120396 0.3048)
			(stroke
				(width 0.1)
				(type default)
			)
			(layer "B.Fab")
		)
		(fp_line
			(start -0.12065 -0.3048)
			(end -0.67945 -0.3048)
			(stroke
				(width 0.1)
				(type default)
			)
			(layer "B.Fab")
		)
		(fp_line
			(start -0.12065 -0.2794)
			(end -0.12065 -0.3048)
			(stroke
				(width 0.1)
				(type default)
			)
			(layer "B.Fab")
		)
		(fp_line
			(start -0.120396 0.2794)
			(end 0.12065 0.2794)
			(stroke
				(width 0.1)
				(type default)
			)
			(layer "B.Fab")
		)
		(fp_line
			(start -0.120396 0.3048)
			(end -0.120396 0.2794)
			(stroke
				(width 0.1)
				(type default)
			)
			(layer "B.Fab")
		)
		(fp_line
			(start 0.12065 -0.305054)
			(end 0.12065 -0.2794)
			(stroke
				(width 0.1)
				(type default)
			)
			(layer "B.Fab")
		)
		(fp_line
			(start 0.12065 -0.2794)
			(end -0.12065 -0.2794)
			(stroke
				(width 0.1)
				(type default)
			)
			(layer "B.Fab")
		)
		(fp_line
			(start 0.12065 0.2794)
			(end 0.12065 0.3048)
			(stroke
				(width 0.1)
				(type default)
			)
			(layer "B.Fab")
		)
		(fp_line
			(start 0.12065 0.3048)
			(end 0.67945 0.3048)
			(stroke
				(width 0.1)
				(type default)
			)
			(layer "B.Fab")
		)
		(fp_line
			(start 0.67945 -0.305054)
			(end 0.12065 -0.305054)
			(stroke
				(width 0.1)
				(type default)
			)
			(layer "B.Fab")
		)
		(fp_line
			(start 0.67945 0.3048)
			(end 0.67945 -0.305054)
			(stroke
				(width 0.1)
				(type default)
			)
			(layer "B.Fab")
		)
		(pad "1" smd circle
			(at 0.40005 0 180)
			(size 0 0)
			(layers "B.Cu" "B.Mask" "B.Paste")
			(net "M_BMC_DDR4_MCLK_DP")
		)
		(pad "2" smd circle
			(at -0.40005 0 180)
			(size 0 0)
			(layers "B.Cu" "B.Mask" "B.Paste")
			(net "M_BMC_DDR4_MCLK_C")
		)
	)
)
